(kicad_pcb
	(version 20260206)
	(generator "pcbnew")
	(generator_version "10.0")
	(general
		(thickness 1.6)
		(legacy_teardrops no)
	)
	(paper "A4")
	(title_block
		(title "pdpb — Lightning_PDPB_BRD.brd")
		(comment 1 "Lightning (Wiwynn / Facebook NVMe JBOF) / footprints 1-6 of 1140")
	)
	(layers
		(0 "F.Cu" signal "TOP")
		(4 "In1.Cu" signal "L2GND")
		(6 "In2.Cu" signal "L3")
		(8 "In3.Cu" signal "L4VCC")
		(10 "In4.Cu" signal "L5VCC")
		(12 "In5.Cu" signal "L6")
		(14 "In6.Cu" signal "L7GND")
		(2 "B.Cu" signal "BOTTOM")
		(9 "F.Adhes" user "F.Adhesive")
		(11 "B.Adhes" user "B.Adhesive")
		(13 "F.Paste" user "Package Geometry/Pastemask Top")
		(15 "B.Paste" user "Package Geometry/Pastemask Bottom")
		(5 "F.SilkS" user "Ref Des/Silkscreen Top")
		(7 "B.SilkS" user "Ref Des/Silkscreen Bottom")
		(1 "F.Mask" user "Board Geometry/Soldermask Top")
		(3 "B.Mask" user "Board Geometry/Soldermask Bottom")
		(17 "Dwgs.User" user "User.Drawings")
		(19 "Cmts.User" user "User.Comments")
		(21 "Eco1.User" user "User.Eco1")
		(23 "Eco2.User" user "User.Eco2")
		(25 "Edge.Cuts" user "Board Geometry/Outline")
		(27 "Margin" user)
		(31 "F.CrtYd" user "Package Geometry/Place Bound Top")
		(29 "B.CrtYd" user "Package Geometry/Place Bound Bottom")
		(35 "F.Fab" user "Ref Des/Assembly Top")
		(33 "B.Fab" user "Ref Des/Assembly Bottom")
	)
	(footprint ""
		(layer "F.Cu")
		(at 214.757 -88.9 -90)
		(property "Reference" "U13"
			(at 0 0 270)
			(layer "F.SilkS")
			(hide yes)
			(effects
				(font
					(size 1.27 1.27)
				)
			)
		)
		(property "Value" "P2003EVG-GP"
			(at 0 -11.1252 270)
			(unlocked yes)
			(layer "F.Fab")
			(hide yes)
			(effects
				(font
					(size 1.016 1.016)
					(thickness 0.1524)
				)
			)
		)
		(property "Device Type" "SOIC8H79"
			(at 0 -12.6492 270)
			(unlocked yes)
			(layer "F.Fab")
			(hide yes)
			(effects
				(font
					(size 1.016 1.016)
					(thickness 0.1524)
				)
			)
		)
		(duplicate_pad_numbers_are_jumpers no)
		(fp_line
			(start -2.6162 3.429)
			(end -2.6162 1.4732)
			(stroke
				(width 0.4064)
				(type default)
			)
			(layer "F.SilkS")
		)
		(fp_line
			(start -2.7432 1.4224)
			(end 2.1336 1.4224)
			(stroke
				(width 0.1524)
				(type default)
			)
			(layer "F.SilkS")
		)
		(fp_line
			(start 2.1336 1.4224)
			(end 2.1336 -1.4224)
			(stroke
				(width 0.1524)
				(type default)
			)
			(layer "F.SilkS")
		)
		(fp_line
			(start -2.2352 0)
			(end -2.7432 0.508)
			(stroke
				(width 0.1524)
				(type default)
			)
			(layer "F.SilkS")
		)
		(fp_line
			(start -2.7432 -0.508)
			(end -2.2352 0)
			(stroke
				(width 0.1524)
				(type default)
			)
			(layer "F.SilkS")
		)
		(fp_line
			(start -2.7432 -1.4224)
			(end -2.7432 1.4224)
			(stroke
				(width 0.1524)
				(type default)
			)
			(layer "F.SilkS")
		)
		(fp_line
			(start 2.1336 -1.4224)
			(end -2.7432 -1.4224)
			(stroke
				(width 0.1524)
				(type default)
			)
			(layer "F.SilkS")
		)
		(fp_poly
			(pts
				(xy 2.2098 -1.4224) (xy 2.2098 1.4224) (xy -2.2225 1.4224) (xy -2.2225 -1.4224)
			)
			(stroke
				(width 0)
				(type default)
			)
			(fill yes)
			(layer "F.SilkS")
		)
		(fp_rect
			(start -2.4511 2.9972)
			(end 2.4511 -2.9972)
			(stroke
				(width 0)
				(type default)
			)
			(fill no)
			(layer "F.CrtYd")
		)
		(fp_poly
			(pts
				(xy -2.8194 3.6322) (xy -2.8194 -3.6322) (xy 2.8194 -3.6322) (xy 2.8194 -2.2987) (xy 2.4511 -2.2987)
				(xy 2.4511 -2.9972) (xy -2.4511 -2.9972) (xy -2.4511 2.9972) (xy 2.4511 2.9972) (xy 2.4511 -2.286)
				(xy 2.8194 -2.286) (xy 2.8194 3.6322)
			)
			(stroke
				(width 0)
				(type default)
			)
			(fill no)
			(layer "F.CrtYd")
		)
		(fp_rect
			(start -2.8194 3.6322)
			(end 2.8194 -3.6322)
			(stroke
				(width 0)
				(type default)
			)
			(fill no)
			(layer "F.Fab")
		)
		(pad "1" smd rect
			(at -1.905 2.54 270)
			(size 0.635 1.651)
			(layers "F.Cu" "F.Mask" "F.Paste")
			(net "P12V")
		)
		(pad "2" smd rect
			(at -0.635 2.54 270)
			(size 0.635 1.651)
			(layers "F.Cu" "F.Mask" "F.Paste")
			(net "P12V")
		)
		(pad "3" smd rect
			(at 0.635 2.54 270)
			(size 0.635 1.651)
			(layers "F.Cu" "F.Mask" "F.Paste")
			(net "P12V")
		)
		(pad "4" smd rect
			(at 1.905 2.54 270)
			(size 0.635 1.651)
			(layers "F.Cu" "F.Mask" "F.Paste")
			(net "SW_SSD4_N")
		)
		(pad "5" smd rect
			(at 1.905 -2.54 270)
			(size 0.635 1.651)
			(layers "F.Cu" "F.Mask" "F.Paste")
			(net "P12V_SSD4")
		)
		(pad "6" smd rect
			(at 0.635 -2.54 270)
			(size 0.635 1.651)
			(layers "F.Cu" "F.Mask" "F.Paste")
			(net "P12V_SSD4")
		)
		(pad "7" smd rect
			(at -0.635 -2.54 270)
			(size 0.635 1.651)
			(layers "F.Cu" "F.Mask" "F.Paste")
			(net "P12V_SSD4")
		)
		(pad "8" smd rect
			(at -1.905 -2.54 270)
			(size 0.635 1.651)
			(layers "F.Cu" "F.Mask" "F.Paste")
			(net "P12V_SSD4")
		)
	)
	(footprint ""
		(layer "F.Cu")
		(at 16.129 -61.33211)
		(property "Reference" "Q98"
			(at 0 0 0)
			(layer "F.SilkS")
			(hide yes)
			(effects
				(font
					(size 1.27 1.27)
				)
			)
		)
		(property "Value" "2N7002A-7-GP"
			(at 0.127 -8.9662 0)
			(unlocked yes)
			(layer "F.Fab")
			(hide yes)
			(effects
				(font
					(size 1.016 1.016)
					(thickness 0.1524)
				)
			)
		)
		(property "Device Type" "SOT23DGS2D4H48"
			(at 0.127 -10.4902 0)
			(unlocked yes)
			(layer "F.Fab")
			(hide yes)
			(effects
				(font
					(size 1.016 1.016)
					(thickness 0.1524)
				)
			)
		)
		(duplicate_pad_numbers_are_jumpers no)
		(fp_line
			(start -1.651 -1.778)
			(end -1.651 1.778)
			(stroke
				(width 0.1524)
				(type default)
			)
			(layer "F.SilkS")
		)
		(fp_line
			(start -1.651 1.778)
			(end 1.651 1.778)
			(stroke
				(width 0.1524)
				(type default)
			)
			(layer "F.SilkS")
		)
		(fp_line
			(start 1.651 -1.778)
			(end -1.651 -1.778)
			(stroke
				(width 0.1524)
				(type default)
			)
			(layer "F.SilkS")
		)
		(fp_line
			(start 1.651 1.778)
			(end 1.651 -1.778)
			(stroke
				(width 0.1524)
				(type default)
			)
			(layer "F.SilkS")
		)
		(fp_poly
			(pts
				(xy -1.778 1.8796) (xy -1.778 -1.8796) (xy 1.778 -1.8796) (xy 1.778 1.8796)
			)
			(stroke
				(width 0)
				(type default)
			)
			(fill no)
			(layer "F.CrtYd")
		)
		(fp_poly
			(pts
				(xy -1.778 1.8796) (xy -1.778 -1.8796) (xy 1.778 -1.8796) (xy 1.778 1.8796)
			)
			(stroke
				(width 0)
				(type default)
			)
			(fill no)
			(layer "F.Fab")
		)
		(pad "D" smd custom
			(at 0 -0.9525)
			(size 0.1905 0.1905)
			(layers "F.Cu" "F.Mask" "F.Paste")
			(net "SSD_ACT_DR14_MOS_N")
			(options
				(clearance outline)
				(anchor circle)
			)
			(primitives
				(gr_poly
					(pts
						(arc
							(start -0.1778 0.5715)
							(mid -0.321484 0.511984)
							(end -0.381 0.3683)
						)
						(arc
							(start -0.381 -0.3683)
							(mid -0.321484 -0.511984)
							(end -0.1778 -0.5715)
						)
						(arc
							(start 0.1778 -0.5715)
							(mid 0.321484 -0.511984)
							(end 0.381 -0.3683)
						)
						(arc
							(start 0.381 0.3683)
							(mid 0.321484 0.511984)
							(end 0.1778 0.5715)
						)
					)
					(width 0)
					(fill yes)
				)
			)
		)
		(pad "G" smd custom
			(at -0.98425 0.9525)
			(size 0.1905 0.1905)
			(layers "F.Cu" "F.Mask" "F.Paste")
			(net "ATTN_LED_DR14_AND_R")
			(options
				(clearance outline)
				(anchor circle)
			)
			(primitives
				(gr_poly
					(pts
						(arc
							(start -0.1778 0.5715)
							(mid -0.321484 0.511984)
							(end -0.381 0.3683)
						)
						(arc
							(start -0.381 -0.3683)
							(mid -0.321484 -0.511984)
							(end -0.1778 -0.5715)
						)
						(arc
							(start 0.1778 -0.5715)
							(mid 0.321484 -0.511984)
							(end 0.381 -0.3683)
						)
						(arc
							(start 0.381 0.3683)
							(mid 0.321484 0.511984)
							(end 0.1778 0.5715)
						)
					)
					(width 0)
					(fill yes)
				)
			)
		)
		(pad "S" smd custom
			(at 0.98425 0.9525)
			(size 0.1905 0.1905)
			(layers "F.Cu" "F.Mask" "F.Paste")
			(net "SSD_ACT_DR14_R")
			(options
				(clearance outline)
				(anchor circle)
			)
			(primitives
				(gr_poly
					(pts
						(arc
							(start -0.1778 0.5715)
							(mid -0.321484 0.511984)
							(end -0.381 0.3683)
						)
						(arc
							(start -0.381 -0.3683)
							(mid -0.321484 -0.511984)
							(end -0.1778 -0.5715)
						)
						(arc
							(start 0.1778 -0.5715)
							(mid 0.321484 -0.511984)
							(end 0.381 -0.3683)
						)
						(arc
							(start 0.381 0.3683)
							(mid 0.321484 0.511984)
							(end 0.1778 0.5715)
						)
					)
					(width 0)
					(fill yes)
				)
			)
		)
	)
	(footprint ""
		(layer "F.Cu")
		(at 82.931 -105.918 90)
		(property "Reference" "SR955"
			(at 0 0 90)
			(layer "F.SilkS")
			(hide yes)
			(effects
				(font
					(size 1.27 1.27)
				)
			)
		)
		(property "Value" "4K7R2F-GP"
			(at 0.064008 -3.993896 90)
			(unlocked yes)
			(layer "F.Fab")
			(hide yes)
			(effects
				(font
					(size 1.016 1.016)
					(thickness 0.1524)
				)
			)
		)
		(property "Device Type" "R402H16"
			(at 0.064008 -5.517896 90)
			(unlocked yes)
			(layer "F.Fab")
			(hide yes)
			(effects
				(font
					(size 1.016 1.016)
					(thickness 0.1524)
				)
			)
		)
		(duplicate_pad_numbers_are_jumpers no)
		(fp_line
			(start 0.508 -0.9398)
			(end -0.508 -0.9398)
			(stroke
				(width 0.1524)
				(type default)
			)
			(layer "F.SilkS")
		)
		(fp_line
			(start -0.508 -0.9398)
			(end -0.508 0.9398)
			(stroke
				(width 0.1524)
				(type default)
			)
			(layer "F.SilkS")
		)
		(fp_rect
			(start -0.508 0.9398)
			(end 0.508 -0.9398)
			(stroke
				(width 0)
				(type default)
			)
			(fill no)
			(layer "F.CrtYd")
		)
		(fp_rect
			(start -0.508 0.9398)
			(end 0.508 -0.9398)
			(stroke
				(width 0)
				(type default)
			)
			(fill no)
			(layer "F.Fab")
		)
		(pad "1" smd custom
			(at 0 -0.4445 90)
			(size 0.1397 0.1397)
			(layers "F.Cu" "F.Mask" "F.Paste")
			(net "VDD_DIFF_4")
			(options
				(clearance outline)
				(anchor circle)
			)
			(primitives
				(gr_poly
					(pts
						(arc
							(start -0.1778 -0.2794)
							(mid -0.249642 -0.249642)
							(end -0.2794 -0.1778)
						)
						(arc
							(start -0.2794 0.1778)
							(mid -0.249642 0.249642)
							(end -0.1778 0.2794)
						)
						(arc
							(start 0.1778 0.2794)
							(mid 0.249642 0.249642)
							(end 0.2794 0.1778)
						)
						(arc
							(start 0.2794 -0.1778)
							(mid 0.249642 -0.249642)
							(end 0.1778 -0.2794)
						)
					)
					(width 0)
					(fill yes)
				)
			)
		)
		(pad "2" smd custom
			(at 0 0.4445 90)
			(size 0.1397 0.1397)
			(layers "F.Cu" "F.Mask" "F.Paste")
			(net "CLK_BUF_EU4_HIBW_BYPM_LOBW#")
			(options
				(clearance outline)
				(anchor circle)
			)
			(primitives
				(gr_poly
					(pts
						(arc
							(start -0.1778 -0.2794)
							(mid -0.249642 -0.249642)
							(end -0.2794 -0.1778)
						)
						(arc
							(start -0.2794 0.1778)
							(mid -0.249642 0.249642)
							(end -0.1778 0.2794)
						)
						(arc
							(start 0.1778 0.2794)
							(mid 0.249642 0.249642)
							(end 0.2794 0.1778)
						)
						(arc
							(start 0.2794 -0.1778)
							(mid 0.249642 -0.249642)
							(end 0.1778 -0.2794)
						)
					)
					(width 0)
					(fill yes)
				)
			)
		)
	)
	(footprint ""
		(layer "F.Cu")
		(at 227.450396 -245.341902 90)
		(property "Reference" "R9932"
			(at 0 0 90)
			(layer "F.SilkS")
			(hide yes)
			(effects
				(font
					(size 1.27 1.27)
				)
			)
		)
		(property "Value" "4K7R2J-2-GP"
			(at 0.064008 -3.993896 90)
			(unlocked yes)
			(layer "F.Fab")
			(hide yes)
			(effects
				(font
					(size 1.016 1.016)
					(thickness 0.1524)
				)
			)
		)
		(property "Device Type" "R402H16"
			(at 0.064008 -5.517896 90)
			(unlocked yes)
			(layer "F.Fab")
			(hide yes)
			(effects
				(font
					(size 1.016 1.016)
					(thickness 0.1524)
				)
			)
		)
		(duplicate_pad_numbers_are_jumpers no)
		(fp_line
			(start 0.508 -0.9398)
			(end -0.508 -0.9398)
			(stroke
				(width 0.1524)
				(type default)
			)
			(layer "F.SilkS")
		)
		(fp_line
			(start -0.508 -0.9398)
			(end -0.508 0.9398)
			(stroke
				(width 0.1524)
				(type default)
			)
			(layer "F.SilkS")
		)
		(fp_rect
			(start -0.508 0.9398)
			(end 0.508 -0.9398)
			(stroke
				(width 0)
				(type default)
			)
			(fill no)
			(layer "F.CrtYd")
		)
		(fp_rect
			(start -0.508 0.9398)
			(end 0.508 -0.9398)
			(stroke
				(width 0)
				(type default)
			)
			(fill no)
			(layer "F.Fab")
		)
		(pad "1" smd custom
			(at 0 -0.4445 90)
			(size 0.1397 0.1397)
			(layers "F.Cu" "F.Mask" "F.Paste")
			(net "P3V3")
			(options
				(clearance outline)
				(anchor circle)
			)
			(primitives
				(gr_poly
					(pts
						(arc
							(start -0.1778 -0.2794)
							(mid -0.249642 -0.249642)
							(end -0.2794 -0.1778)
						)
						(arc
							(start -0.2794 0.1778)
							(mid -0.249642 0.249642)
							(end -0.1778 0.2794)
						)
						(arc
							(start 0.1778 0.2794)
							(mid 0.249642 0.249642)
							(end 0.2794 0.1778)
						)
						(arc
							(start 0.2794 -0.1778)
							(mid 0.249642 -0.249642)
							(end 0.1778 -0.2794)
						)
					)
					(width 0)
					(fill yes)
				)
			)
		)
		(pad "2" smd custom
			(at 0 0.4445 90)
			(size 0.1397 0.1397)
			(layers "F.Cu" "F.Mask" "F.Paste")
			(net "SSD_ACT_DR2_MOS_N")
			(options
				(clearance outline)
				(anchor circle)
			)
			(primitives
				(gr_poly
					(pts
						(arc
							(start -0.1778 -0.2794)
							(mid -0.249642 -0.249642)
							(end -0.2794 -0.1778)
						)
						(arc
							(start -0.2794 0.1778)
							(mid -0.249642 0.249642)
							(end -0.1778 0.2794)
						)
						(arc
							(start 0.1778 0.2794)
							(mid 0.249642 0.249642)
							(end 0.2794 0.1778)
						)
						(arc
							(start 0.2794 -0.1778)
							(mid 0.249642 -0.249642)
							(end 0.1778 -0.2794)
						)
					)
					(width 0)
					(fill yes)
				)
			)
		)
	)
	(footprint ""
		(layer "F.Cu")
		(at 43.20032 -450.907912)
		(property "Reference" "R9938"
			(at 0 0 0)
			(layer "F.SilkS")
			(hide yes)
			(effects
				(font
					(size 1.27 1.27)
				)
			)
		)
		(property "Value" "4K7R2J-2-GP"
			(at 0.064008 -3.993896 0)
			(unlocked yes)
			(layer "F.Fab")
			(hide yes)
			(effects
				(font
					(size 1.016 1.016)
					(thickness 0.1524)
				)
			)
		)
		(property "Device Type" "R402H16"
			(at 0.064008 -5.517896 0)
			(unlocked yes)
			(layer "F.Fab")
			(hide yes)
			(effects
				(font
					(size 1.016 1.016)
					(thickness 0.1524)
				)
			)
		)
		(duplicate_pad_numbers_are_jumpers no)
		(fp_line
			(start -0.508 -0.9398)
			(end -0.508 0.9398)
			(stroke
				(width 0.1524)
				(type default)
			)
			(layer "F.SilkS")
		)
		(fp_line
			(start 0.508 -0.9398)
			(end -0.508 -0.9398)
			(stroke
				(width 0.1524)
				(type default)
			)
			(layer "F.SilkS")
		)
		(fp_rect
			(start -0.508 0.9398)
			(end 0.508 -0.9398)
			(stroke
				(width 0)
				(type default)
			)
			(fill no)
			(layer "F.CrtYd")
		)
		(fp_rect
			(start -0.508 0.9398)
			(end 0.508 -0.9398)
			(stroke
				(width 0)
				(type default)
			)
			(fill no)
			(layer "F.Fab")
		)
		(pad "1" smd custom
			(at 0 -0.4445)
			(size 0.1397 0.1397)
			(layers "F.Cu" "F.Mask" "F.Paste")
			(net "P3V3")
			(options
				(clearance outline)
				(anchor circle)
			)
			(primitives
				(gr_poly
					(pts
						(arc
							(start -0.1778 -0.2794)
							(mid -0.249642 -0.249642)
							(end -0.2794 -0.1778)
						)
						(arc
							(start -0.2794 0.1778)
							(mid -0.249642 0.249642)
							(end -0.1778 0.2794)
						)
						(arc
							(start 0.1778 0.2794)
							(mid 0.249642 0.249642)
							(end 0.2794 0.1778)
						)
						(arc
							(start 0.2794 -0.1778)
							(mid 0.249642 -0.249642)
							(end 0.1778 -0.2794)
						)
					)
					(width 0)
					(fill yes)
				)
			)
		)
		(pad "2" smd custom
			(at 0 0.4445)
			(size 0.1397 0.1397)
			(layers "F.Cu" "F.Mask" "F.Paste")
			(net "SSD_ACT_DR5_MOS_N")
			(options
				(clearance outline)
				(anchor circle)
			)
			(primitives
				(gr_poly
					(pts
						(arc
							(start -0.1778 -0.2794)
							(mid -0.249642 -0.249642)
							(end -0.2794 -0.1778)
						)
						(arc
							(start -0.2794 0.1778)
							(mid -0.249642 0.249642)
							(end -0.1778 0.2794)
						)
						(arc
							(start 0.1778 0.2794)
							(mid 0.249642 0.249642)
							(end 0.2794 0.1778)
						)
						(arc
							(start 0.2794 -0.1778)
							(mid 0.249642 -0.249642)
							(end 0.1778 -0.2794)
						)
					)
					(width 0)
					(fill yes)
				)
			)
		)
	)
	(footprint ""
		(layer "F.Cu")
		(at 219.837 -91.44 180)
		(property "Reference" "PC1202"
			(at 0 0 180)
			(layer "F.SilkS")
			(hide yes)
			(effects
				(font
					(size 1.27 1.27)
				)
			)
		)
		(property "Value" "SCD1U50V3KX-GP"
			(at 0 -2.8194 180)
			(unlocked yes)
			(layer "F.Fab")
			(hide yes)
			(effects
				(font
					(size 1.016 1.016)
					(thickness 0.1524)
				)
			)
		)
		(property "Device Type" "C603H36"
			(at 0 -4.3434 180)
			(unlocked yes)
			(layer "F.Fab")
			(hide yes)
			(effects
				(font
					(size 1.016 1.016)
					(thickness 0.1524)
				)
			)
		)
		(duplicate_pad_numbers_are_jumpers no)
		(fp_line
			(start 0.508 0)
			(end -0.508 0)
			(stroke
				(width 0.2032)
				(type default)
			)
			(layer "F.SilkS")
		)
		(fp_rect
			(start -0.5842 1.3335)
			(end 0.5842 -1.3335)
			(stroke
				(width 0)
				(type default)
			)
			(fill no)
			(layer "F.CrtYd")
		)
		(fp_rect
			(start -0.5842 1.3335)
			(end 0.5842 -1.3335)
			(stroke
				(width 0)
				(type default)
			)
			(fill no)
			(layer "F.Fab")
		)
		(pad "1" smd custom
			(at 0 -0.762 180)
			(size 0.2159 0.2159)
			(layers "F.Cu" "F.Mask" "F.Paste")
			(net "P12V_SSD4")
			(options
				(clearance outline)
				(anchor circle)
			)
			(primitives
				(gr_poly
					(pts
						(arc
							(start -0.3302 -0.4318)
							(mid -0.402042 -0.402042)
							(end -0.4318 -0.3302)
						)
						(arc
							(start -0.4318 0.3302)
							(mid -0.402042 0.402042)
							(end -0.3302 0.4318)
						)
						(arc
							(start 0.3302 0.4318)
							(mid 0.402042 0.402042)
							(end 0.4318 0.3302)
						)
						(arc
							(start 0.4318 -0.3302)
							(mid 0.402042 -0.402042)
							(end 0.3302 -0.4318)
						)
					)
					(width 0)
					(fill yes)
				)
			)
		)
		(pad "2" smd custom
			(at 0 0.762 180)
			(size 0.2159 0.2159)
			(layers "F.Cu" "F.Mask" "F.Paste")
			(net "GND")
			(options
				(clearance outline)
				(anchor circle)
			)
			(primitives
				(gr_poly
					(pts
						(arc
							(start -0.3302 -0.4318)
							(mid -0.402042 -0.402042)
							(end -0.4318 -0.3302)
						)
						(arc
							(start -0.4318 0.3302)
							(mid -0.402042 0.402042)
							(end -0.3302 0.4318)
						)
						(arc
							(start 0.3302 0.4318)
							(mid 0.402042 0.402042)
							(end 0.4318 0.3302)
						)
						(arc
							(start 0.4318 -0.3302)
							(mid 0.402042 -0.402042)
							(end 0.3302 -0.4318)
						)
					)
					(width 0)
					(fill yes)
				)
			)
		)
	)
)
